FILE_TYPE = MULTI_PHYS_TABLE;

PART 'NX3L2267GM'

{========================================================================================}
:VALUE        | PART_TYPE | MATERIAL | PART_NUMBER    = STANDARD    | LIFECYCLE     | PART_NUMBER   | JEDEC_TYPE | DESCRIPTION               | MANUFTR | MANUF_PN     | RD_CMPLS_LVL | CMPLS_LVL | FROM_PJ    | CLASS | DIP_SMD | DATA                 | EE_CHECK_LIST | FP_ECN | PSL | CREATOR | STATUS | MSD | ESD_CDM | ESD_HBM | ESD_MM | PIN_LENGTH_SHORT_PIN | PIN_LENGTH_LONG_PIN | CREATEDAY  ;
{========================================================================================}
 'NX3L2267GM' | 'SMLF'    | 'IC'     | 'AL002267000'(!) = ''               | ''               | 'AL002267000' |'XQFN10'| 'IC(10P)NX3L2267GM(XQFN)' | 'NXP'   | 'NX3L2267GM' | 'EP(V1)'     | ''        | 'F0C-IVES' | 'IC'  | ''      | 'NXP_NX3L2267GM.pdf' | ''            | ''     | ''  | ''      | ''     | ''  | ''      | ''      | ''     | '0 MILS'             | '0 MILS'            | '20210622'
 'NX3L2267GM' | 'SMLF'    | 'EMPTY'  | 'AL002267000'(!) = ''               | ''               | 'AL002267000' |'XQFN10'| 'IC(10P)NX3L2267GM(XQFN)' | 'NXP'   | 'NX3L2267GM' | 'EP(V1)'     | ''        | 'F0C-IVES' | 'IC'  | ''      | 'NXP_NX3L2267GM.pdf' | ''            | ''     | ''  | ''      | ''     | ''  | ''      | ''      | ''     | '0 MILS'             | '0 MILS'            | '20210622'

END_PART

END.

